# T6G (Grand Teton) — schematic netlist excerpt (pin names and nets, part order shuffled) for the footprints in the layout excerpt that follows; sources: Cadence DE-HDL packaged netlist, KiCad conversion of 04192023_DAF0TMB3IC0_F0TG_MB_C_brd_V02_OCP.brd

PC113_C1P0_6  Q_CAP  2.2UF 10V 10% X6S  pkg C0402  page 203 : A = PVDDCR_CPU1_P0_PVCC ; B = GND
R6094  Q_RES  0 5% EMPTY  pkg 0402LF  page 80 : A = E1S_0_PERST1_CLKREQ_R_N ; B = E1S_0_PERST1_CLKREQ_N

(kicad_pcb
	(version 20260206)
	(generator "pcbnew")
	(generator_version "10.0")
	(general
		(thickness 1.6)
		(legacy_teardrops no)
	)
	(paper "A4")
	(title_block
		(title "04192023_DAF0TMB3IC0_F0TG_MB_C_brd_V02_OCP.brd")
		(comment 1 "Grand Teton / footprints 3077-3078 of 8354")
	)
	(layers
		(0 "F.Cu" signal "TOP")
		(4 "In1.Cu" signal "GND")
		(6 "In2.Cu" signal "IN1")
		(8 "In3.Cu" signal "GND1")
		(10 "In4.Cu" signal "IN2")
		(12 "In5.Cu" signal "GND2")
		(14 "In6.Cu" signal "IN3")
		(16 "In7.Cu" signal "GND3")
		(18 "In8.Cu" signal "VCC")
		(20 "In9.Cu" signal "VCC1")
		(22 "In10.Cu" signal "GND4")
		(24 "In11.Cu" signal "IN4")
		(26 "In12.Cu" signal "GND5")
		(28 "In13.Cu" signal "IN5")
		(30 "In14.Cu" signal "GND6")
		(32 "In15.Cu" signal "IN6")
		(34 "In16.Cu" signal "GND7")
		(2 "B.Cu" signal "BOTTOM")
		(9 "F.Adhes" user "F.Adhesive")
		(11 "B.Adhes" user "B.Adhesive")
		(13 "F.Paste" user "Package Geometry/Pastemask Top")
		(15 "B.Paste" user "Package Geometry/Pastemask Bottom")
		(5 "F.SilkS" user "Ref Des/Silkscreen Top")
		(7 "B.SilkS" user "Ref Des/Silkscreen Bottom")
		(1 "F.Mask" user "Board Geometry/Soldermask Top")
		(3 "B.Mask" user "Board Geometry/Soldermask Bottom")
		(17 "Dwgs.User" user "User.Drawings")
		(19 "Cmts.User" user "User.Comments")
		(21 "Eco1.User" user "User.Eco1")
		(23 "Eco2.User" user "User.Eco2")
		(25 "Edge.Cuts" user "Board Geometry/Outline")
		(27 "Margin" user)
		(31 "F.CrtYd" user "Package Geometry/Place Bound Top")
		(29 "B.CrtYd" user "Package Geometry/Place Bound Bottom")
		(35 "F.Fab" user "Ref Des/Assembly Top")
		(33 "B.Fab" user "Ref Des/Assembly Bottom")
	)
	(footprint ""
		(layer "F.Cu")
		(at 347.983048 -339.932772 -90)
		(property "Reference" "PC113_C1P0_6"
			(at 0 0 270)
			(layer "F.SilkS")
			(hide yes)
			(effects
				(font
					(size 1.27 1.27)
				)
			)
		)
		(property "Value" ""
			(at 0 0 270)
			(layer "F.Fab")
			(effects
				(font
					(size 1.27 1.27)
				)
			)
		)
		(duplicate_pad_numbers_are_jumpers no)
		(fp_line
			(start -0.7874 0.4064)
			(end -0.7874 -0.4064)
			(stroke
				(width 0.1524)
				(type default)
			)
			(layer "F.SilkS")
		)
		(fp_line
			(start 0.7874 0.4064)
			(end -0.7874 0.4064)
			(stroke
				(width 0.1524)
				(type default)
			)
			(layer "F.SilkS")
		)
		(fp_line
			(start -0.7874 -0.4064)
			(end 0.7874 -0.4064)
			(stroke
				(width 0.1524)
				(type default)
			)
			(layer "F.SilkS")
		)
		(fp_line
			(start 0.7874 -0.4064)
			(end 0.7874 0.4064)
			(stroke
				(width 0.1524)
				(type default)
			)
			(layer "F.SilkS")
		)
		(fp_line
			(start -0.67945 0.3048)
			(end -0.67945 -0.305054)
			(stroke
				(width 0.1)
				(type default)
			)
			(layer "F.Fab")
		)
		(fp_line
			(start -0.12065 0.3048)
			(end -0.67945 0.3048)
			(stroke
				(width 0.1)
				(type default)
			)
			(layer "F.Fab")
		)
		(fp_line
			(start 0.120396 0.3048)
			(end 0.120396 0.2794)
			(stroke
				(width 0.1)
				(type default)
			)
			(layer "F.Fab")
		)
		(fp_line
			(start 0.67945 0.3048)
			(end 0.120396 0.3048)
			(stroke
				(width 0.1)
				(type default)
			)
			(layer "F.Fab")
		)
		(fp_line
			(start -0.12065 0.2794)
			(end -0.12065 0.3048)
			(stroke
				(width 0.1)
				(type default)
			)
			(layer "F.Fab")
		)
		(fp_line
			(start 0.120396 0.2794)
			(end -0.12065 0.2794)
			(stroke
				(width 0.1)
				(type default)
			)
			(layer "F.Fab")
		)
		(fp_line
			(start -0.12065 -0.2794)
			(end 0.12065 -0.2794)
			(stroke
				(width 0.1)
				(type default)
			)
			(layer "F.Fab")
		)
		(fp_line
			(start 0.12065 -0.2794)
			(end 0.12065 -0.3048)
			(stroke
				(width 0.1)
				(type default)
			)
			(layer "F.Fab")
		)
		(fp_line
			(start 0.12065 -0.3048)
			(end 0.67945 -0.3048)
			(stroke
				(width 0.1)
				(type default)
			)
			(layer "F.Fab")
		)
		(fp_line
			(start 0.67945 -0.3048)
			(end 0.67945 0.3048)
			(stroke
				(width 0.1)
				(type default)
			)
			(layer "F.Fab")
		)
		(fp_line
			(start -0.67945 -0.305054)
			(end -0.12065 -0.305054)
			(stroke
				(width 0.1)
				(type default)
			)
			(layer "F.Fab")
		)
		(fp_line
			(start -0.12065 -0.305054)
			(end -0.12065 -0.2794)
			(stroke
				(width 0.1)
				(type default)
			)
			(layer "F.Fab")
		)
		(pad "1" smd circle
			(at -0.40005 0 270)
			(size 0 0)
			(layers "F.Cu" "F.Mask" "F.Paste")
			(net "PVDDCR_CPU1_P0_PVCC")
		)
		(pad "2" smd circle
			(at 0.40005 0 270)
			(size 0 0)
			(layers "F.Cu" "F.Mask" "F.Paste")
			(net "GND")
		)
	)
	(footprint ""
		(layer "F.Cu")
		(at 163.703 -111.216948 180)
		(property "Reference" "R6094"
			(at 0 0 180)
			(layer "F.SilkS")
			(hide yes)
			(effects
				(font
					(size 1.27 1.27)
				)
			)
		)
		(property "Value" ""
			(at 0 0 180)
			(layer "F.Fab")
			(effects
				(font
					(size 1.27 1.27)
				)
			)
		)
		(duplicate_pad_numbers_are_jumpers no)
		(fp_line
			(start 0.7874 0.4064)
			(end -0.7874 0.4064)
			(stroke
				(width 0.1524)
				(type default)
			)
			(layer "F.SilkS")
		)
		(fp_line
			(start 0.7874 -0.4064)
			(end 0.7874 0.4064)
			(stroke
				(width 0.1524)
				(type default)
			)
			(layer "F.SilkS")
		)
		(fp_line
			(start -0.7874 0.4064)
			(end -0.7874 -0.4064)
			(stroke
				(width 0.1524)
				(type default)
			)
			(layer "F.SilkS")
		)
		(fp_line
			(start -0.7874 -0.4064)
			(end 0.7874 -0.4064)
			(stroke
				(width 0.1524)
				(type default)
			)
			(layer "F.SilkS")
		)
		(fp_line
			(start 0.67945 0.3048)
			(end 0.120396 0.3048)
			(stroke
				(width 0.1)
				(type default)
			)
			(layer "F.Fab")
		)
		(fp_line
			(start 0.67945 -0.3048)
			(end 0.67945 0.3048)
			(stroke
				(width 0.1)
				(type default)
			)
			(layer "F.Fab")
		)
		(fp_line
			(start 0.12065 -0.2794)
			(end 0.12065 -0.3048)
			(stroke
				(width 0.1)
				(type default)
			)
			(layer "F.Fab")
		)
		(fp_line
			(start 0.12065 -0.3048)
			(end 0.67945 -0.3048)
			(stroke
				(width 0.1)
				(type default)
			)
			(layer "F.Fab")
		)
		(fp_line
			(start 0.120396 0.3048)
			(end 0.120396 0.2794)
			(stroke
				(width 0.1)
				(type default)
			)
			(layer "F.Fab")
		)
		(fp_line
			(start 0.120396 0.2794)
			(end -0.12065 0.2794)
			(stroke
				(width 0.1)
				(type default)
			)
			(layer "F.Fab")
		)
		(fp_line
			(start -0.12065 0.3048)
			(end -0.67945 0.3048)
			(stroke
				(width 0.1)
				(type default)
			)
			(layer "F.Fab")
		)
		(fp_line
			(start -0.12065 0.2794)
			(end -0.12065 0.3048)
			(stroke
				(width 0.1)
				(type default)
			)
			(layer "F.Fab")
		)
		(fp_line
			(start -0.12065 -0.2794)
			(end 0.12065 -0.2794)
			(stroke
				(width 0.1)
				(type default)
			)
			(layer "F.Fab")
		)
		(fp_line
			(start -0.12065 -0.305054)
			(end -0.12065 -0.2794)
			(stroke
				(width 0.1)
				(type default)
			)
			(layer "F.Fab")
		)
		(fp_line
			(start -0.67945 0.3048)
			(end -0.67945 -0.305054)
			(stroke
				(width 0.1)
				(type default)
			)
			(layer "F.Fab")
		)
		(fp_line
			(start -0.67945 -0.305054)
			(end -0.12065 -0.305054)
			(stroke
				(width 0.1)
				(type default)
			)
			(layer "F.Fab")
		)
		(pad "1" smd circle
			(at -0.40005 0 180)
			(size 0 0)
			(layers "F.Cu" "F.Mask" "F.Paste")
			(net "E1S_0_PERST1_CLKREQ_R_N")
		)
		(pad "2" smd circle
			(at 0.40005 0 180)
			(size 0 0)
			(layers "F.Cu" "F.Mask" "F.Paste")
			(net "E1S_0_PERST1_CLKREQ_N")
		)
	)
)
